(kicad_pcb
	(version 20241229)
	(generator "pcbnew")
	(generator_version "9.0")
	(general
		(thickness 1.292)
		(legacy_teardrops no)
	)
	(paper "A4")
	(title_block
		(title "LPDDR5 Testbed")
		(date "2023-12-19")
		(rev "1.0.0")
		(comment 9 "footprint 16 of 160 (J1), pads 1-94 of 264")
	)
	(layers
		(0 "F.Cu" signal)
		(4 "In1.Cu" power)
		(6 "In2.Cu" power)
		(8 "In3.Cu" signal)
		(10 "In4.Cu" signal)
		(2 "B.Cu" signal)
		(9 "F.Adhes" user "F.Adhesive")
		(11 "B.Adhes" user "B.Adhesive")
		(13 "F.Paste" user)
		(15 "B.Paste" user)
		(5 "F.SilkS" user "F.Silkscreen")
		(7 "B.SilkS" user "B.Silkscreen")
		(1 "F.Mask" user)
		(3 "B.Mask" user)
		(17 "Dwgs.User" user "User.Drawings")
		(19 "Cmts.User" user "User.Comments")
		(21 "Eco1.User" user "User.Eco1")
		(23 "Eco2.User" user "User.Eco2")
		(25 "Edge.Cuts" user)
		(27 "Margin" user)
		(31 "F.CrtYd" user "F.Courtyard")
		(29 "B.CrtYd" user "B.Courtyard")
		(35 "F.Fab" user)
		(33 "B.Fab" user)
	)
	(footprint "lpddr5-testbed-footprints:Edge_Conn_Bus_DDR5_SODIMM"
		(locked yes)
		(layer "F.Cu")
		(at 99.975 100)
		(descr "SODIMM DDR5 Edge Connector")
		(tags "SODIMM DDR5 Edge Connector")
		(property "Reference" "J1"
			(at 0 -4.2 0)
			(unlocked yes)
			(layer "F.SilkS")
			(effects
				(font
					(size 0.7 0.7)
					(thickness 0.15)
				)
				(justify left bottom)
			)
		)
		(property "Value" "Edge_Conn_Bus_DDR5_SODIMM_1xDetectPin"
			(at 0 1 0)
			(layer "F.Fab")
			(effects
				(font
					(size 0.7 0.7)
					(thickness 0.15)
				)
				(justify left bottom)
			)
		)
		(property "Author" "Antmicro"
			(at 0 0 0)
			(layer "F.Fab")
			(hide yes)
			(effects
				(font
					(size 1 1)
					(thickness 0.15)
				)
			)
		)
		(property "License" "Apache-2.0"
			(at 0 0 0)
			(layer "F.Fab")
			(hide yes)
			(effects
				(font
					(size 1 1)
					(thickness 0.15)
				)
			)
		)
		(property "MPN" ""
			(at 0 0 0)
			(layer "F.Fab")
			(hide yes)
			(effects
				(font
					(size 1 1)
					(thickness 0.15)
				)
			)
		)
		(property "Manufacturer" ""
			(at 0 0 0)
			(layer "F.Fab")
			(hide yes)
			(effects
				(font
					(size 1 1)
					(thickness 0.15)
				)
			)
		)
		(sheetname "SODIMM")
		(sheetfile "sodim.kicad_sch")
		(attr exclude_from_pos_files)
		(pad "" np_thru_hole circle
			(at 1.1 -6)
			(size 1.5 1.5)
			(drill 1.5)
			(layers "*.Mask")
		)
		(pad "" np_thru_hole circle
			(at 68.51 -6)
			(size 1.6 1.6)
			(drill 1.6)
			(layers "*.Mask")
		)
		(pad "1" smd rect
			(at 1.425 -1.375)
			(size 0.35 2.35)
			(layers "F.Cu" "F.Mask")
			(net 5 "+5V")
			(pinfunction "VIN_BULK")
			(pintype "passive")
		)
		(pad "2" smd rect
			(at 1.675 -1.375 180)
			(size 0.35 2.35)
			(layers "B.Cu" "B.Mask")
			(net 116 "unconnected-(J1-Pad2)")
			(pinfunction "HSA")
			(pintype "passive+no_connect")
		)
		(pad "3" smd rect
			(at 1.925 -1.375)
			(size 0.35 2.35)
			(layers "F.Cu" "F.Mask")
			(net 5 "+5V")
			(pinfunction "VIN_BULK")
			(pintype "passive")
		)
		(pad "4" smd rect
			(at 2.175 -1.375 180)
			(size 0.35 2.35)
			(layers "B.Cu" "B.Mask")
			(net 18 "/SODIMM/HSCL")
			(pinfunction "HSCL")
			(pintype "passive")
		)
		(pad "5" smd rect
			(at 2.425 -1.375)
			(size 0.35 2.35)
			(layers "F.Cu" "F.Mask")
			(net 42 "unconnected-(J1-Pad5)")
			(pinfunction "RFU")
			(pintype "passive+no_connect")
		)
		(pad "6" smd rect
			(at 2.675 -1.375 180)
			(size 0.35 2.35)
			(layers "B.Cu" "B.Mask")
			(net 19 "/SODIMM/HSDA")
			(pinfunction "HSDA")
			(pintype "passive")
		)
		(pad "7" smd rect
			(at 2.925 -1.375)
			(size 0.35 2.35)
			(layers "F.Cu" "F.Mask")
			(net 41 "/Power supply/PWRGD")
			(pinfunction "PWR_GOOD")
			(pintype "passive")
		)
		(pad "8" smd rect
			(at 3.175 -1.375 180)
			(size 0.35 2.35)
			(layers "B.Cu" "B.Mask")
			(net 20 "/Power supply/PWR_EN")
			(pinfunction "PWR_EN")
			(pintype "passive")
		)
		(pad "9" smd rect
			(at 3.425 -1.375)
			(size 0.35 2.35)
			(layers "F.Cu" "F.Mask")
			(net 14 "GND")
			(pinfunction "VSS")
			(pintype "passive")
		)
		(pad "10" smd rect
			(at 3.675 -1.375 180)
			(size 0.35 2.35)
			(layers "B.Cu" "B.Mask")
			(net 14 "GND")
			(pinfunction "VSS")
			(pintype "passive")
		)
		(pad "11" smd rect
			(at 3.925 -1.375)
			(size 0.35 2.35)
			(layers "F.Cu" "F.Mask")
			(net 187 "/SODIMM/LPDDR5_IN_A.DQ8")
			(pinfunction "DQ0_A")
			(pintype "passive")
		)
		(pad "12" smd rect
			(at 4.175 -1.375 180)
			(size 0.35 2.35)
			(layers "B.Cu" "B.Mask")
			(net 185 "/SODIMM/LPDDR5_IN_A.DQ10")
			(pinfunction "DQ1_A")
			(pintype "passive")
		)
		(pad "13" smd rect
			(at 4.425 -1.375)
			(size 0.35 2.35)
			(layers "F.Cu" "F.Mask")
			(net 14 "GND")
			(pinfunction "VSS")
			(pintype "passive")
		)
		(pad "14" smd rect
			(at 4.675 -1.375 180)
			(size 0.35 2.35)
			(layers "B.Cu" "B.Mask")
			(net 14 "GND")
			(pinfunction "VSS")
			(pintype "passive")
		)
		(pad "15" smd rect
			(at 4.925 -1.375)
			(size 0.35 2.35)
			(layers "F.Cu" "F.Mask")
			(net 186 "/SODIMM/LPDDR5_IN_A.DQ9")
			(pinfunction "DQ2_A")
			(pintype "passive")
		)
		(pad "16" smd rect
			(at 5.175 -1.375 180)
			(size 0.35 2.35)
			(layers "B.Cu" "B.Mask")
			(net 184 "/SODIMM/LPDDR5_IN_A.DQ11")
			(pinfunction "DQ3_A")
			(pintype "passive")
		)
		(pad "17" smd rect
			(at 5.425 -1.375)
			(size 0.35 2.35)
			(layers "F.Cu" "F.Mask")
			(net 14 "GND")
			(pinfunction "VSS")
			(pintype "passive")
		)
		(pad "18" smd rect
			(at 5.675 -1.375 180)
			(size 0.35 2.35)
			(layers "B.Cu" "B.Mask")
			(net 14 "GND")
			(pinfunction "VSS")
			(pintype "passive")
		)
		(pad "19" smd rect
			(at 5.925 -1.375)
			(size 0.35 2.35)
			(layers "F.Cu" "F.Mask")
			(net 118 "/SODIMM/LPDDR5_IN_A.DMI1")
			(pinfunction "DM0_A_n")
			(pintype "passive")
		)
		(pad "20" smd rect
			(at 6.175 -1.375 180)
			(size 0.35 2.35)
			(layers "B.Cu" "B.Mask")
			(net 182 "/SODIMM/LPDDR5_IN_A.WCK1_N")
			(pinfunction "DQS0_A_C")
			(pintype "passive")
		)
		(pad "21" smd rect
			(at 6.425 -1.375)
			(size 0.35 2.35)
			(layers "F.Cu" "F.Mask")
			(net 14 "GND")
			(pinfunction "VSS")
			(pintype "passive")
		)
		(pad "22" smd rect
			(at 6.675 -1.375 180)
			(size 0.35 2.35)
			(layers "B.Cu" "B.Mask")
			(net 181 "/SODIMM/LPDDR5_IN_A.WCK1_P")
			(pinfunction "DQS0_A_t")
			(pintype "passive")
		)
		(pad "23" smd rect
			(at 6.925 -1.375)
			(size 0.35 2.35)
			(layers "F.Cu" "F.Mask")
			(net 177 "/SODIMM/LPDDR5_IN_A.DQ15")
			(pinfunction "DQ4_A")
			(pintype "passive")
		)
		(pad "24" smd rect
			(at 7.175 -1.375 180)
			(size 0.35 2.35)
			(layers "B.Cu" "B.Mask")
			(net 14 "GND")
			(pinfunction "VSS")
			(pintype "passive")
		)
		(pad "25" smd rect
			(at 7.425 -1.375)
			(size 0.35 2.35)
			(layers "F.Cu" "F.Mask")
			(net 14 "GND")
			(pinfunction "VSS")
			(pintype "passive")
		)
		(pad "26" smd rect
			(at 7.675 -1.375 180)
			(size 0.35 2.35)
			(layers "B.Cu" "B.Mask")
			(net 180 "/SODIMM/LPDDR5_IN_A.DQ14")
			(pinfunction "DQ5_A")
			(pintype "passive")
		)
		(pad "27" smd rect
			(at 7.925 -1.375)
			(size 0.35 2.35)
			(layers "F.Cu" "F.Mask")
			(net 178 "/SODIMM/LPDDR5_IN_A.DQ12")
			(pinfunction "DQ6_A")
			(pintype "passive")
		)
		(pad "28" smd rect
			(at 8.175 -1.375 180)
			(size 0.35 2.35)
			(layers "B.Cu" "B.Mask")
			(net 14 "GND")
			(pinfunction "VSS")
			(pintype "passive")
		)
		(pad "29" smd rect
			(at 8.425 -1.375)
			(size 0.35 2.35)
			(layers "F.Cu" "F.Mask")
			(net 14 "GND")
			(pinfunction "VSS")
			(pintype "passive")
		)
		(pad "30" smd rect
			(at 8.675 -1.375 180)
			(size 0.35 2.35)
			(layers "B.Cu" "B.Mask")
			(net 179 "/SODIMM/LPDDR5_IN_A.DQ13")
			(pinfunction "DQ7_A")
			(pintype "passive")
		)
		(pad "31" smd rect
			(at 8.925 -1.375)
			(size 0.35 2.35)
			(layers "F.Cu" "F.Mask")
			(net 128 "/LPDDR5/LPDDR5_A.DQ8")
			(pinfunction "DQ8_A")
			(pintype "passive")
		)
		(pad "32" smd rect
			(at 9.175 -1.375 180)
			(size 0.35 2.35)
			(layers "B.Cu" "B.Mask")
			(net 14 "GND")
			(pinfunction "VSS")
			(pintype "passive")
		)
		(pad "33" smd rect
			(at 9.425 -1.375)
			(size 0.35 2.35)
			(layers "F.Cu" "F.Mask")
			(net 14 "GND")
			(pinfunction "VSS")
			(pintype "passive")
		)
		(pad "34" smd rect
			(at 9.675 -1.375 180)
			(size 0.35 2.35)
			(layers "B.Cu" "B.Mask")
			(net 139 "/LPDDR5/LPDDR5_A.DQ10")
			(pinfunction "DQ09_A")
			(pintype "passive")
		)
		(pad "35" smd rect
			(at 9.925 -1.375)
			(size 0.35 2.35)
			(layers "F.Cu" "F.Mask")
			(net 172 "/LPDDR5/LPDDR5_A.DQ9")
			(pinfunction "DQ10_A")
			(pintype "passive")
		)
		(pad "36" smd rect
			(at 10.175 -1.375 180)
			(size 0.35 2.35)
			(layers "B.Cu" "B.Mask")
			(net 14 "GND")
			(pinfunction "VSS")
			(pintype "passive")
		)
		(pad "37" smd rect
			(at 10.425 -1.375)
			(size 0.35 2.35)
			(layers "F.Cu" "F.Mask")
			(net 14 "GND")
			(pinfunction "VSS")
			(pintype "passive")
		)
		(pad "38" smd rect
			(at 10.675 -1.375 180)
			(size 0.35 2.35)
			(layers "B.Cu" "B.Mask")
			(net 183 "/LPDDR5/LPDDR5_A.DQ11")
			(pinfunction "DQ11_A")
			(pintype "passive")
		)
		(pad "39" smd rect
			(at 10.925 -1.375)
			(size 0.35 2.35)
			(layers "F.Cu" "F.Mask")
			(net 188 "/LPDDR5/LPDDR5_A.RDQS1_N")
			(pinfunction "DQS1_A_C")
			(pintype "passive")
		)
		(pad "40" smd rect
			(at 11.175 -1.375 180)
			(size 0.35 2.35)
			(layers "B.Cu" "B.Mask")
			(net 14 "GND")
			(pinfunction "VSS")
			(pintype "passive")
		)
		(pad "41" smd rect
			(at 11.425 -1.375)
			(size 0.35 2.35)
			(layers "F.Cu" "F.Mask")
			(net 189 "/LPDDR5/LPDDR5_A.RDQS1_P")
			(pinfunction "DQS1_A_t")
			(pintype "passive")
		)
		(pad "42" smd rect
			(at 11.675 -1.375 180)
			(size 0.35 2.35)
			(layers "B.Cu" "B.Mask")
			(net 190 "/LPDDR5/LPDDR5_A.DMI1")
			(pinfunction "DM1_A_n")
			(pintype "passive")
		)
		(pad "43" smd rect
			(at 11.925 -1.375)
			(size 0.35 2.35)
			(layers "F.Cu" "F.Mask")
			(net 14 "GND")
			(pinfunction "VSS")
			(pintype "passive")
		)
		(pad "44" smd rect
			(at 12.175 -1.375 180)
			(size 0.35 2.35)
			(layers "B.Cu" "B.Mask")
			(net 14 "GND")
			(pinfunction "VSS")
			(pintype "passive")
		)
		(pad "45" smd rect
			(at 12.425 -1.375)
			(size 0.35 2.35)
			(layers "F.Cu" "F.Mask")
			(net 191 "/LPDDR5/LPDDR5_A.DQ15")
			(pinfunction "DQ12_A")
			(pintype "passive")
		)
		(pad "46" smd rect
			(at 12.675 -1.375 180)
			(size 0.35 2.35)
			(layers "B.Cu" "B.Mask")
			(net 192 "/LPDDR5/LPDDR5_A.DQ14")
			(pinfunction "DQ13_A")
			(pintype "passive")
		)
		(pad "47" smd rect
			(at 12.925 -1.375)
			(size 0.35 2.35)
			(layers "F.Cu" "F.Mask")
			(net 14 "GND")
			(pinfunction "VSS")
			(pintype "passive")
		)
		(pad "48" smd rect
			(at 13.175 -1.375 180)
			(size 0.35 2.35)
			(layers "B.Cu" "B.Mask")
			(net 14 "GND")
			(pinfunction "VSS")
			(pintype "passive")
		)
		(pad "49" smd rect
			(at 13.425 -1.375)
			(size 0.35 2.35)
			(layers "F.Cu" "F.Mask")
			(net 193 "/LPDDR5/LPDDR5_A.DQ12")
			(pinfunction "DQ14_A")
			(pintype "passive")
		)
		(pad "50" smd rect
			(at 13.675 -1.375 180)
			(size 0.35 2.35)
			(layers "B.Cu" "B.Mask")
			(net 194 "/LPDDR5/LPDDR5_A.DQ13")
			(pinfunction "DQ15_A")
			(pintype "passive")
		)
		(pad "51" smd rect
			(at 13.925 -1.375)
			(size 0.35 2.35)
			(layers "F.Cu" "F.Mask")
			(net 14 "GND")
			(pinfunction "VSS")
			(pintype "passive")
		)
		(pad "52" smd rect
			(at 14.175 -1.375 180)
			(size 0.35 2.35)
			(layers "B.Cu" "B.Mask")
			(net 14 "GND")
			(pinfunction "VSS")
			(pintype "passive")
		)
		(pad "53" smd rect
			(at 14.425 -1.375)
			(size 0.35 2.35)
			(layers "F.Cu" "F.Mask")
			(net 176 "/SODIMM/LPDDR5_IN_A.DQ5")
			(pinfunction "DQ16_A")
			(pintype "passive")
		)
		(pad "54" smd rect
			(at 14.675 -1.375 180)
			(size 0.35 2.35)
			(layers "B.Cu" "B.Mask")
			(net 175 "/SODIMM/LPDDR5_IN_A.DQ4")
			(pinfunction "DQ17_A")
			(pintype "passive")
		)
		(pad "55" smd rect
			(at 14.925 -1.375)
			(size 0.35 2.35)
			(layers "F.Cu" "F.Mask")
			(net 14 "GND")
			(pinfunction "VSS")
			(pintype "passive")
		)
		(pad "56" smd rect
			(at 15.175 -1.375 180)
			(size 0.35 2.35)
			(layers "B.Cu" "B.Mask")
			(net 14 "GND")
			(pinfunction "VSS")
			(pintype "passive")
		)
		(pad "57" smd rect
			(at 15.425 -1.375)
			(size 0.35 2.35)
			(layers "F.Cu" "F.Mask")
			(net 174 "/SODIMM/LPDDR5_IN_A.DQ6")
			(pinfunction "DQ18_A")
			(pintype "passive")
		)
		(pad "58" smd rect
			(at 15.675 -1.375 180)
			(size 0.35 2.35)
			(layers "B.Cu" "B.Mask")
			(net 173 "/SODIMM/LPDDR5_IN_A.DQ7")
			(pinfunction "DQ19_A")
			(pintype "passive")
		)
		(pad "59" smd rect
			(at 15.925 -1.375)
			(size 0.35 2.35)
			(layers "F.Cu" "F.Mask")
			(net 14 "GND")
			(pinfunction "VSS")
			(pintype "passive")
		)
		(pad "60" smd rect
			(at 16.175 -1.375 180)
			(size 0.35 2.35)
			(layers "B.Cu" "B.Mask")
			(net 14 "GND")
			(pinfunction "VSS")
			(pintype "passive")
		)
		(pad "61" smd rect
			(at 16.425 -1.375)
			(size 0.35 2.35)
			(layers "F.Cu" "F.Mask")
			(net 119 "/SODIMM/LPDDR5_IN_A.DMI0")
			(pinfunction "DM2_A_n")
			(pintype "passive")
		)
		(pad "62" smd rect
			(at 16.675 -1.375 180)
			(size 0.35 2.35)
			(layers "B.Cu" "B.Mask")
			(net 171 "/SODIMM/LPDDR5_IN_A.WCK0_N")
			(pinfunction "DQS2_A_C")
			(pintype "passive")
		)
		(pad "63" smd rect
			(at 16.925 -1.375)
			(size 0.35 2.35)
			(layers "F.Cu" "F.Mask")
			(net 14 "GND")
			(pinfunction "VSS")
			(pintype "passive")
		)
		(pad "64" smd rect
			(at 17.175 -1.375 180)
			(size 0.35 2.35)
			(layers "B.Cu" "B.Mask")
			(net 170 "/SODIMM/LPDDR5_IN_A.WCK0_P")
			(pinfunction "DQS2_A_t")
			(pintype "passive")
		)
		(pad "65" smd rect
			(at 17.425 -1.375)
			(size 0.35 2.35)
			(layers "F.Cu" "F.Mask")
			(net 169 "/SODIMM/LPDDR5_IN_A.DQ3")
			(pinfunction "DQ20_A")
			(pintype "passive")
		)
		(pad "66" smd rect
			(at 17.675 -1.375 180)
			(size 0.35 2.35)
			(layers "B.Cu" "B.Mask")
			(net 14 "GND")
			(pinfunction "VSS")
			(pintype "passive")
		)
		(pad "67" smd rect
			(at 17.925 -1.375)
			(size 0.35 2.35)
			(layers "F.Cu" "F.Mask")
			(net 14 "GND")
			(pinfunction "VSS")
			(pintype "passive")
		)
		(pad "68" smd rect
			(at 18.175 -1.375 180)
			(size 0.35 2.35)
			(layers "B.Cu" "B.Mask")
			(net 168 "/SODIMM/LPDDR5_IN_A.DQ1")
			(pinfunction "DQ21_A")
			(pintype "passive")
		)
		(pad "69" smd rect
			(at 18.425 -1.375)
			(size 0.35 2.35)
			(layers "F.Cu" "F.Mask")
			(net 167 "/SODIMM/LPDDR5_IN_A.DQ2")
			(pinfunction "DQ22_A")
			(pintype "passive")
		)
		(pad "70" smd rect
			(at 18.675 -1.375 180)
			(size 0.35 2.35)
			(layers "B.Cu" "B.Mask")
			(net 14 "GND")
			(pinfunction "VSS")
			(pintype "passive")
		)
		(pad "71" smd rect
			(at 18.925 -1.375)
			(size 0.35 2.35)
			(layers "F.Cu" "F.Mask")
			(net 14 "GND")
			(pinfunction "VSS")
			(pintype "passive")
		)
		(pad "72" smd rect
			(at 19.175 -1.375 180)
			(size 0.35 2.35)
			(layers "B.Cu" "B.Mask")
			(net 166 "/SODIMM/LPDDR5_IN_A.DQ0")
			(pinfunction "DQ23_A")
			(pintype "passive")
		)
		(pad "73" smd rect
			(at 19.425 -1.375)
			(size 0.35 2.35)
			(layers "F.Cu" "F.Mask")
			(net 197 "/LPDDR5/LPDDR5_A.DQ5")
			(pinfunction "DQ24_A")
			(pintype "passive")
		)
		(pad "74" smd rect
			(at 19.675 -1.375 180)
			(size 0.35 2.35)
			(layers "B.Cu" "B.Mask")
			(net 14 "GND")
			(pinfunction "VSS")
			(pintype "passive")
		)
		(pad "75" smd rect
			(at 19.925 -1.375)
			(size 0.35 2.35)
			(layers "F.Cu" "F.Mask")
			(net 14 "GND")
			(pinfunction "VSS")
			(pintype "passive")
		)
		(pad "76" smd rect
			(at 20.175 -1.375 180)
			(size 0.35 2.35)
			(layers "B.Cu" "B.Mask")
			(net 198 "/LPDDR5/LPDDR5_A.DQ4")
			(pinfunction "DQ25_A")
			(pintype "passive")
		)
		(pad "77" smd rect
			(at 20.425 -1.375)
			(size 0.35 2.35)
			(layers "F.Cu" "F.Mask")
			(net 196 "/LPDDR5/LPDDR5_A.DQ6")
			(pinfunction "DQ26_A")
			(pintype "passive")
		)
		(pad "78" smd rect
			(at 20.675 -1.375 180)
			(size 0.35 2.35)
			(layers "B.Cu" "B.Mask")
			(net 14 "GND")
			(pinfunction "VSS")
			(pintype "passive")
		)
		(pad "79" smd rect
			(at 20.925 -1.375)
			(size 0.35 2.35)
			(layers "F.Cu" "F.Mask")
			(net 14 "GND")
			(pinfunction "VSS")
			(pintype "passive")
		)
		(pad "80" smd rect
			(at 21.175 -1.375 180)
			(size 0.35 2.35)
			(layers "B.Cu" "B.Mask")
			(net 195 "/LPDDR5/LPDDR5_A.DQ7")
			(pinfunction "DQ27_A")
			(pintype "passive")
		)
		(pad "81" smd rect
			(at 21.425 -1.375)
			(size 0.35 2.35)
			(layers "F.Cu" "F.Mask")
			(net 199 "/LPDDR5/LPDDR5_A.RDQS0_N")
			(pinfunction "DQS3_A_C")
			(pintype "passive")
		)
		(pad "82" smd rect
			(at 21.675 -1.375 180)
			(size 0.35 2.35)
			(layers "B.Cu" "B.Mask")
			(net 14 "GND")
			(pinfunction "VSS")
			(pintype "passive")
		)
		(pad "83" smd rect
			(at 21.925 -1.375)
			(size 0.35 2.35)
			(layers "F.Cu" "F.Mask")
			(net 200 "/LPDDR5/LPDDR5_A.RDQS0_P")
			(pinfunction "DQS3_A_t")
			(pintype "passive")
		)
		(pad "84" smd rect
			(at 22.175 -1.375 180)
			(size 0.35 2.35)
			(layers "B.Cu" "B.Mask")
			(net 201 "/LPDDR5/LPDDR5_A.DMI0")
			(pinfunction "DM3_A_n")
			(pintype "passive")
		)
		(pad "85" smd rect
			(at 22.425 -1.375)
			(size 0.35 2.35)
			(layers "F.Cu" "F.Mask")
			(net 14 "GND")
			(pinfunction "VSS")
			(pintype "passive")
		)
		(pad "86" smd rect
			(at 22.675 -1.375 180)
			(size 0.35 2.35)
			(layers "B.Cu" "B.Mask")
			(net 14 "GND")
			(pinfunction "VSS")
			(pintype "passive")
		)
		(pad "87" smd rect
			(at 22.925 -1.375)
			(size 0.35 2.35)
			(layers "F.Cu" "F.Mask")
			(net 202 "/LPDDR5/LPDDR5_A.DQ3")
			(pinfunction "DQ28_A")
			(pintype "passive")
		)
		(pad "88" smd rect
			(at 23.175 -1.375 180)
			(size 0.35 2.35)
			(layers "B.Cu" "B.Mask")
			(net 204 "/LPDDR5/LPDDR5_A.DQ1")
			(pinfunction "DQ29_A")
			(pintype "passive")
		)
		(pad "89" smd rect
			(at 23.425 -1.375)
			(size 0.35 2.35)
			(layers "F.Cu" "F.Mask")
			(net 14 "GND")
			(pinfunction "VSS")
			(pintype "passive")
		)
		(pad "90" smd rect
			(at 23.675 -1.375 180)
			(size 0.35 2.35)
			(layers "B.Cu" "B.Mask")
			(net 14 "GND")
			(pinfunction "VSS")
			(pintype "passive")
		)
		(pad "91" smd rect
			(at 23.925 -1.375)
			(size 0.35 2.35)
			(layers "F.Cu" "F.Mask")
			(net 203 "/LPDDR5/LPDDR5_A.DQ2")
			(pinfunction "DQ30_A")
			(pintype "passive")
		)
		(pad "92" smd rect
			(at 24.175 -1.375 180)
			(size 0.35 2.35)
			(layers "B.Cu" "B.Mask")
			(net 205 "/LPDDR5/LPDDR5_A.DQ0")
			(pinfunction "DQ31_A")
			(pintype "passive")
		)
	)
)
